# T6G (Grand Teton) — schematic netlist excerpt (pin names and nets, part order shuffled) for the footprints in the layout excerpt that follows; sources: Cadence DE-HDL packaged netlist, KiCad conversion of 04192023_DAF0TMB3IC0_F0TG_MB_C_brd_V02_OCP.brd

U176  LTC4307CMS8  EMPTY  pkg MSOP8  page 248
  ENABLE  = SMB_BMC_SWB_EN_R2
  SCL_OUT  = I3C_BMC_SWB_BUF_R_SCL
  SCL_IN  = I3C_BMC_SWB_R_SCL
  GND  = GND
  READY  = NC
  SDA_IN  = I3C_BMC_SWB_R_SDA
  SDA_OUT  = I3C_BMC_SWB_BUF_R_SDA
  VCC  = P3V3_AUX

C710  Q_CAP_DIFFBUS  DIFF BUS_0.22UF 6.3V 20% X6S  pkg C0201  page 66 : \1\ = P5E_CPU1_P1_TX_C_DN<15> ; \2\ = P5E_CPU1_P1_TX_DN<15>

(kicad_pcb
	(version 20260206)
	(generator "pcbnew")
	(generator_version "10.0")
	(general
		(thickness 1.6)
		(legacy_teardrops no)
	)
	(paper "A4")
	(title_block
		(title "04192023_DAF0TMB3IC0_F0TG_MB_C_brd_V02_OCP.brd")
		(comment 1 "Grand Teton / footprints 2867-2868 of 8354")
	)
	(layers
		(0 "F.Cu" signal "TOP")
		(4 "In1.Cu" signal "GND")
		(6 "In2.Cu" signal "IN1")
		(8 "In3.Cu" signal "GND1")
		(10 "In4.Cu" signal "IN2")
		(12 "In5.Cu" signal "GND2")
		(14 "In6.Cu" signal "IN3")
		(16 "In7.Cu" signal "GND3")
		(18 "In8.Cu" signal "VCC")
		(20 "In9.Cu" signal "VCC1")
		(22 "In10.Cu" signal "GND4")
		(24 "In11.Cu" signal "IN4")
		(26 "In12.Cu" signal "GND5")
		(28 "In13.Cu" signal "IN5")
		(30 "In14.Cu" signal "GND6")
		(32 "In15.Cu" signal "IN6")
		(34 "In16.Cu" signal "GND7")
		(2 "B.Cu" signal "BOTTOM")
		(9 "F.Adhes" user "F.Adhesive")
		(11 "B.Adhes" user "B.Adhesive")
		(13 "F.Paste" user "Package Geometry/Pastemask Top")
		(15 "B.Paste" user "Package Geometry/Pastemask Bottom")
		(5 "F.SilkS" user "Ref Des/Silkscreen Top")
		(7 "B.SilkS" user "Ref Des/Silkscreen Bottom")
		(1 "F.Mask" user "Board Geometry/Soldermask Top")
		(3 "B.Mask" user "Board Geometry/Soldermask Bottom")
		(17 "Dwgs.User" user "User.Drawings")
		(19 "Cmts.User" user "User.Comments")
		(21 "Eco1.User" user "User.Eco1")
		(23 "Eco2.User" user "User.Eco2")
		(25 "Edge.Cuts" user "Board Geometry/Outline")
		(27 "Margin" user)
		(31 "F.CrtYd" user "Package Geometry/Place Bound Top")
		(29 "B.CrtYd" user "Package Geometry/Place Bound Bottom")
		(35 "F.Fab" user "Ref Des/Assembly Top")
		(33 "B.Fab" user "Ref Des/Assembly Bottom")
	)
	(footprint ""
		(layer "F.Cu")
		(at 288.970212 -426.357542)
		(property "Reference" "U176"
			(at -0.771906 -2.687574 0)
			(unlocked yes)
			(layer "F.SilkS")
			(effects
				(font
					(size 0.7874 0.5842)
					(thickness 0.1524)
				)
				(justify left)
			)
		)
		(property "Value" ""
			(at 0 0 0)
			(layer "F.Fab")
			(effects
				(font
					(size 1.27 1.27)
				)
			)
		)
		(duplicate_pad_numbers_are_jumpers no)
		(fp_line
			(start -1.3716 -1.524)
			(end -0.508 -1.524)
			(stroke
				(width 0.1524)
				(type default)
			)
			(layer "F.SilkS")
		)
		(fp_line
			(start -1.3716 1.524)
			(end -1.3716 -1.524)
			(stroke
				(width 0.1524)
				(type default)
			)
			(layer "F.SilkS")
		)
		(fp_line
			(start -0.508 -1.524)
			(end 0 -1.016)
			(stroke
				(width 0.1524)
				(type default)
			)
			(layer "F.SilkS")
		)
		(fp_line
			(start 0 -1.016)
			(end 0.508 -1.524)
			(stroke
				(width 0.1524)
				(type default)
			)
			(layer "F.SilkS")
		)
		(fp_line
			(start 0.508 -1.524)
			(end 1.3716 -1.524)
			(stroke
				(width 0.1524)
				(type default)
			)
			(layer "F.SilkS")
		)
		(fp_line
			(start 1.3716 -1.524)
			(end 1.3716 1.524)
			(stroke
				(width 0.1524)
				(type default)
			)
			(layer "F.SilkS")
		)
		(fp_line
			(start 1.3716 1.524)
			(end -1.3716 1.524)
			(stroke
				(width 0.1524)
				(type default)
			)
			(layer "F.SilkS")
		)
		(fp_poly
			(pts
				(xy -2.082292 -2.04724) (xy -1.457452 -2.04724) (xy -1.78562 -1.49352)
			)
			(stroke
				(width 0)
				(type default)
			)
			(fill yes)
			(layer "F.SilkS")
		)
		(fp_line
			(start -2.54 -1.0668)
			(end -1.5494 -1.0668)
			(stroke
				(width 0.1)
				(type default)
			)
			(layer "F.Fab")
		)
		(fp_line
			(start -2.54 1.0668)
			(end -2.54 -1.0668)
			(stroke
				(width 0.1)
				(type default)
			)
			(layer "F.Fab")
		)
		(fp_line
			(start -1.5494 -1.524)
			(end 1.5494 -1.524)
			(stroke
				(width 0.1)
				(type default)
			)
			(layer "F.Fab")
		)
		(fp_line
			(start -1.5494 -1.0668)
			(end -1.5494 -1.524)
			(stroke
				(width 0.1)
				(type default)
			)
			(layer "F.Fab")
		)
		(fp_line
			(start -1.5494 1.0668)
			(end -2.54 1.0668)
			(stroke
				(width 0.1)
				(type default)
			)
			(layer "F.Fab")
		)
		(fp_line
			(start -1.5494 1.0668)
			(end -1.5494 -1.0668)
			(stroke
				(width 0.1)
				(type default)
			)
			(layer "F.Fab")
		)
		(fp_line
			(start -1.5494 1.524)
			(end -1.5494 1.0668)
			(stroke
				(width 0.1)
				(type default)
			)
			(layer "F.Fab")
		)
		(fp_line
			(start 1.5494 -1.524)
			(end 1.5494 -1.0668)
			(stroke
				(width 0.1)
				(type default)
			)
			(layer "F.Fab")
		)
		(fp_line
			(start 1.5494 -1.0668)
			(end 1.5494 1.0668)
			(stroke
				(width 0.1)
				(type default)
			)
			(layer "F.Fab")
		)
		(fp_line
			(start 1.5494 -1.0668)
			(end 2.54 -1.0668)
			(stroke
				(width 0.1)
				(type default)
			)
			(layer "F.Fab")
		)
		(fp_line
			(start 1.5494 1.0668)
			(end 1.5494 1.524)
			(stroke
				(width 0.1)
				(type default)
			)
			(layer "F.Fab")
		)
		(fp_line
			(start 1.5494 1.524)
			(end -1.5494 1.524)
			(stroke
				(width 0.1)
				(type default)
			)
			(layer "F.Fab")
		)
		(fp_line
			(start 2.54 -1.0668)
			(end 2.54 1.0668)
			(stroke
				(width 0.1)
				(type default)
			)
			(layer "F.Fab")
		)
		(fp_line
			(start 2.54 1.0668)
			(end 1.5494 1.0668)
			(stroke
				(width 0.1)
				(type default)
			)
			(layer "F.Fab")
		)
		(fp_poly
			(pts
				(xy -3.60172 -0.719328) (xy -3.60172 -1.344168) (xy -3.048 -1.016)
			)
			(stroke
				(width 0)
				(type default)
			)
			(fill yes)
			(layer "F.Fab")
		)
		(pad "1" smd rect
			(at -2.232406 -0.975106 270)
			(size 0.3556 1.4224)
			(layers "F.Cu" "F.Mask" "F.Paste")
			(net "SMB_BMC_SWB_EN_R2")
		)
		(pad "2" smd rect
			(at -2.232406 -0.32512 270)
			(size 0.3556 1.4224)
			(layers "F.Cu" "F.Mask" "F.Paste")
			(net "I3C_BMC_SWB_BUF_R_SCL")
		)
		(pad "3" smd rect
			(at -2.232406 0.32512 270)
			(size 0.3556 1.4224)
			(layers "F.Cu" "F.Mask" "F.Paste")
			(net "I3C_BMC_SWB_R_SCL")
		)
		(pad "4" smd rect
			(at -2.232406 0.975106 270)
			(size 0.3556 1.4224)
			(layers "F.Cu" "F.Mask" "F.Paste")
			(net "GND")
		)
		(pad "5" smd rect
			(at 2.232406 0.975106 270)
			(size 0.3556 1.4224)
			(layers "F.Cu" "F.Mask" "F.Paste")
			(net "Net_10762")
		)
		(pad "6" smd rect
			(at 2.232406 0.32512 270)
			(size 0.3556 1.4224)
			(layers "F.Cu" "F.Mask" "F.Paste")
			(net "I3C_BMC_SWB_R_SDA")
		)
		(pad "7" smd rect
			(at 2.232406 -0.32512 270)
			(size 0.3556 1.4224)
			(layers "F.Cu" "F.Mask" "F.Paste")
			(net "I3C_BMC_SWB_BUF_R_SDA")
		)
		(pad "8" smd rect
			(at 2.232406 -0.975106 270)
			(size 0.3556 1.4224)
			(layers "F.Cu" "F.Mask" "F.Paste")
			(net "P3V3_AUX")
		)
	)
	(footprint ""
		(layer "F.Cu")
		(at 102.268782 -380.385828)
		(property "Reference" "C710"
			(at 0 0 0)
			(layer "F.SilkS")
			(hide yes)
			(effects
				(font
					(size 1.27 1.27)
				)
			)
		)
		(property "Value" ""
			(at 0 0 0)
			(layer "F.Fab")
			(effects
				(font
					(size 1.27 1.27)
				)
			)
		)
		(duplicate_pad_numbers_are_jumpers no)
		(fp_line
			(start -0.299974 -0.150114)
			(end 0.299974 -0.150114)
			(stroke
				(width 0.1)
				(type default)
			)
			(layer "F.Fab")
		)
		(fp_line
			(start -0.299974 0.150114)
			(end -0.299974 -0.150114)
			(stroke
				(width 0.1)
				(type default)
			)
			(layer "F.Fab")
		)
		(fp_line
			(start 0.299974 -0.150114)
			(end 0.299974 0.150114)
			(stroke
				(width 0.1)
				(type default)
			)
			(layer "F.Fab")
		)
		(fp_line
			(start 0.299974 0.150114)
			(end -0.299974 0.150114)
			(stroke
				(width 0.1)
				(type default)
			)
			(layer "F.Fab")
		)
		(pad "1" smd rect
			(at -0.2667 0)
			(size 0.3048 0.381)
			(layers "F.Cu" "F.Mask" "F.Paste")
			(net "P5E_CPU1_P1_TX_C_DN<15>")
		)
		(pad "2" smd rect
			(at 0.2667 0)
			(size 0.3048 0.381)
			(layers "F.Cu" "F.Mask" "F.Paste")
			(net "P5E_CPU1_P1_TX_DN<15>")
		)
	)
)
